(kicad_pcb
	(version 20260206)
	(generator "pcbnew")
	(generator_version "10.0")
	(general
		(thickness 1.6)
		(legacy_teardrops no)
	)
	(paper "A4")
	(title_block
		(title "ptb — Lightning_PTB_BRD.brd")
		(comment 1 "Lightning (Wiwynn / Facebook NVMe JBOF) / footprints 8-14 of 61")
	)
	(layers
		(0 "F.Cu" signal "TOP")
		(4 "In1.Cu" signal "L2GND")
		(6 "In2.Cu" signal "L3VCC")
		(2 "B.Cu" signal "BOTTOM")
		(9 "F.Adhes" user "F.Adhesive")
		(11 "B.Adhes" user "B.Adhesive")
		(13 "F.Paste" user "Package Geometry/Pastemask Top")
		(15 "B.Paste" user "Package Geometry/Pastemask Bottom")
		(5 "F.SilkS" user "Ref Des/Silkscreen Top")
		(7 "B.SilkS" user "Ref Des/Silkscreen Bottom")
		(1 "F.Mask" user "Board Geometry/Soldermask Top")
		(3 "B.Mask" user "Board Geometry/Soldermask Bottom")
		(17 "Dwgs.User" user "User.Drawings")
		(19 "Cmts.User" user "User.Comments")
		(21 "Eco1.User" user "User.Eco1")
		(23 "Eco2.User" user "User.Eco2")
		(25 "Edge.Cuts" user "Board Geometry/Outline")
		(27 "Margin" user)
		(31 "F.CrtYd" user "Package Geometry/Place Bound Top")
		(29 "B.CrtYd" user "Package Geometry/Place Bound Bottom")
		(35 "F.Fab" user "Ref Des/Assembly Top")
		(33 "B.Fab" user "Ref Des/Assembly Bottom")
	)
	(footprint ""
		(layer "F.Cu")
		(at 107.061 -47.371 180)
		(property "Reference" "C364"
			(at 0 0 180)
			(layer "F.SilkS")
			(hide yes)
			(effects
				(font
					(size 1.27 1.27)
				)
			)
		)
		(property "Value" "SC47U16V0MX-GP"
			(at -0.00254 -4.78536 180)
			(unlocked yes)
			(layer "F.Fab")
			(hide yes)
			(effects
				(font
					(size 1.016 1.016)
					(thickness 0.1524)
				)
			)
		)
		(property "Device Type" "C1210H107"
			(at -0.00254 -6.38048 180)
			(unlocked yes)
			(layer "F.Fab")
			(hide yes)
			(effects
				(font
					(size 1.016 1.016)
					(thickness 0.1524)
				)
			)
		)
		(duplicate_pad_numbers_are_jumpers no)
		(fp_line
			(start 1.5748 2.3368)
			(end 1.5748 0.762)
			(stroke
				(width 0.1524)
				(type default)
			)
			(layer "F.SilkS")
		)
		(fp_line
			(start 1.5748 -0.762)
			(end 1.5748 -2.3368)
			(stroke
				(width 0.1524)
				(type default)
			)
			(layer "F.SilkS")
		)
		(fp_line
			(start 1.5748 -2.3368)
			(end -1.5748 -2.3368)
			(stroke
				(width 0.1524)
				(type default)
			)
			(layer "F.SilkS")
		)
		(fp_line
			(start -1.5748 2.3368)
			(end 1.5748 2.3368)
			(stroke
				(width 0.1524)
				(type default)
			)
			(layer "F.SilkS")
		)
		(fp_line
			(start -1.5748 0.762)
			(end -1.5748 2.3368)
			(stroke
				(width 0.1524)
				(type default)
			)
			(layer "F.SilkS")
		)
		(fp_line
			(start -1.5748 -2.3368)
			(end -1.5748 -0.762)
			(stroke
				(width 0.1524)
				(type default)
			)
			(layer "F.SilkS")
		)
		(fp_rect
			(start -1.651 2.413)
			(end 1.651 -2.413)
			(stroke
				(width 0)
				(type default)
			)
			(fill no)
			(layer "F.CrtYd")
		)
		(fp_poly
			(pts
				(xy 1.651 2.413) (xy 1.651 -2.413) (xy -1.651 -2.413) (xy -1.651 2.413)
			)
			(stroke
				(width 0)
				(type default)
			)
			(fill no)
			(layer "F.Fab")
		)
		(pad "1" smd rect
			(at 0 -1.4732 180)
			(size 2.794 1.397)
			(layers "F.Cu" "F.Mask" "F.Paste")
			(net "P12V")
		)
		(pad "2" smd rect
			(at 0 1.4732 180)
			(size 2.794 1.397)
			(layers "F.Cu" "F.Mask" "F.Paste")
			(net "GND")
		)
	)
	(footprint ""
		(layer "F.Cu")
		(at 8.079232 -93.708728 90)
		(property "Reference" "R389"
			(at 0 0 90)
			(layer "F.SilkS")
			(hide yes)
			(effects
				(font
					(size 1.27 1.27)
				)
			)
		)
		(property "Value" "0R2J-2-GP"
			(at 0.064008 -3.993896 90)
			(unlocked yes)
			(layer "F.Fab")
			(hide yes)
			(effects
				(font
					(size 1.016 1.016)
					(thickness 0.1524)
				)
			)
		)
		(property "Device Type" "R402H16"
			(at 0.064008 -5.517896 90)
			(unlocked yes)
			(layer "F.Fab")
			(hide yes)
			(effects
				(font
					(size 1.016 1.016)
					(thickness 0.1524)
				)
			)
		)
		(duplicate_pad_numbers_are_jumpers no)
		(fp_line
			(start 0.508 -0.9398)
			(end -0.508 -0.9398)
			(stroke
				(width 0.1524)
				(type default)
			)
			(layer "F.SilkS")
		)
		(fp_line
			(start -0.508 -0.9398)
			(end -0.508 0.9398)
			(stroke
				(width 0.1524)
				(type default)
			)
			(layer "F.SilkS")
		)
		(fp_rect
			(start -0.508 0.9398)
			(end 0.508 -0.9398)
			(stroke
				(width 0)
				(type default)
			)
			(fill no)
			(layer "F.CrtYd")
		)
		(fp_rect
			(start -0.508 0.9398)
			(end 0.508 -0.9398)
			(stroke
				(width 0)
				(type default)
			)
			(fill no)
			(layer "F.Fab")
		)
		(pad "1" smd custom
			(at 0 -0.4445 90)
			(size 0.1397 0.1397)
			(layers "F.Cu" "F.Mask" "F.Paste")
			(net "STRADDLE_I2C_C_SCL")
			(options
				(clearance outline)
				(anchor circle)
			)
			(primitives
				(gr_poly
					(pts
						(arc
							(start -0.1778 -0.2794)
							(mid -0.249642 -0.249642)
							(end -0.2794 -0.1778)
						)
						(arc
							(start -0.2794 0.1778)
							(mid -0.249642 0.249642)
							(end -0.1778 0.2794)
						)
						(arc
							(start 0.1778 0.2794)
							(mid 0.249642 0.249642)
							(end 0.2794 0.1778)
						)
						(arc
							(start 0.2794 -0.1778)
							(mid 0.249642 -0.249642)
							(end 0.1778 -0.2794)
						)
					)
					(width 0)
					(fill yes)
				)
			)
		)
		(pad "2" smd custom
			(at 0 0.4445 90)
			(size 0.1397 0.1397)
			(layers "F.Cu" "F.Mask" "F.Paste")
			(net "I2C_C_SCL")
			(options
				(clearance outline)
				(anchor circle)
			)
			(primitives
				(gr_poly
					(pts
						(arc
							(start -0.1778 -0.2794)
							(mid -0.249642 -0.249642)
							(end -0.2794 -0.1778)
						)
						(arc
							(start -0.2794 0.1778)
							(mid -0.249642 0.249642)
							(end -0.1778 0.2794)
						)
						(arc
							(start 0.1778 0.2794)
							(mid 0.249642 0.249642)
							(end 0.2794 0.1778)
						)
						(arc
							(start 0.2794 -0.1778)
							(mid 0.249642 -0.249642)
							(end 0.1778 -0.2794)
						)
					)
					(width 0)
					(fill yes)
				)
			)
		)
	)
	(footprint ""
		(layer "F.Cu")
		(at 110.49 -47.371 180)
		(property "Reference" "C363"
			(at 0 0 180)
			(layer "F.SilkS")
			(hide yes)
			(effects
				(font
					(size 1.27 1.27)
				)
			)
		)
		(property "Value" "SC47U16V0MX-GP"
			(at -0.00254 -4.78536 180)
			(unlocked yes)
			(layer "F.Fab")
			(hide yes)
			(effects
				(font
					(size 1.016 1.016)
					(thickness 0.1524)
				)
			)
		)
		(property "Device Type" "C1210H107"
			(at -0.00254 -6.38048 180)
			(unlocked yes)
			(layer "F.Fab")
			(hide yes)
			(effects
				(font
					(size 1.016 1.016)
					(thickness 0.1524)
				)
			)
		)
		(duplicate_pad_numbers_are_jumpers no)
		(fp_line
			(start 1.5748 2.3368)
			(end 1.5748 0.762)
			(stroke
				(width 0.1524)
				(type default)
			)
			(layer "F.SilkS")
		)
		(fp_line
			(start 1.5748 -0.762)
			(end 1.5748 -2.3368)
			(stroke
				(width 0.1524)
				(type default)
			)
			(layer "F.SilkS")
		)
		(fp_line
			(start 1.5748 -2.3368)
			(end -1.5748 -2.3368)
			(stroke
				(width 0.1524)
				(type default)
			)
			(layer "F.SilkS")
		)
		(fp_line
			(start -1.5748 2.3368)
			(end 1.5748 2.3368)
			(stroke
				(width 0.1524)
				(type default)
			)
			(layer "F.SilkS")
		)
		(fp_line
			(start -1.5748 0.762)
			(end -1.5748 2.3368)
			(stroke
				(width 0.1524)
				(type default)
			)
			(layer "F.SilkS")
		)
		(fp_line
			(start -1.5748 -2.3368)
			(end -1.5748 -0.762)
			(stroke
				(width 0.1524)
				(type default)
			)
			(layer "F.SilkS")
		)
		(fp_rect
			(start -1.651 2.413)
			(end 1.651 -2.413)
			(stroke
				(width 0)
				(type default)
			)
			(fill no)
			(layer "F.CrtYd")
		)
		(fp_poly
			(pts
				(xy 1.651 2.413) (xy 1.651 -2.413) (xy -1.651 -2.413) (xy -1.651 2.413)
			)
			(stroke
				(width 0)
				(type default)
			)
			(fill no)
			(layer "F.Fab")
		)
		(pad "1" smd rect
			(at 0 -1.4732 180)
			(size 2.794 1.397)
			(layers "F.Cu" "F.Mask" "F.Paste")
			(net "P12V")
		)
		(pad "2" smd rect
			(at 0 1.4732 180)
			(size 2.794 1.397)
			(layers "F.Cu" "F.Mask" "F.Paste")
			(net "GND")
		)
	)
	(footprint ""
		(layer "F.Cu")
		(at 13.38707 -89.94013 180)
		(property "Reference" "R342"
			(at 0 0 180)
			(layer "F.SilkS")
			(hide yes)
			(effects
				(font
					(size 1.27 1.27)
				)
			)
		)
		(property "Value" "10KR2F-2-GP"
			(at 0.064008 -3.993896 180)
			(unlocked yes)
			(layer "F.Fab")
			(hide yes)
			(effects
				(font
					(size 1.016 1.016)
					(thickness 0.1524)
				)
			)
		)
		(property "Device Type" "R402H16"
			(at 0.064008 -5.517896 180)
			(unlocked yes)
			(layer "F.Fab")
			(hide yes)
			(effects
				(font
					(size 1.016 1.016)
					(thickness 0.1524)
				)
			)
		)
		(duplicate_pad_numbers_are_jumpers no)
		(fp_line
			(start 0.508 -0.9398)
			(end -0.508 -0.9398)
			(stroke
				(width 0.1524)
				(type default)
			)
			(layer "F.SilkS")
		)
		(fp_line
			(start -0.508 -0.9398)
			(end -0.508 0.9398)
			(stroke
				(width 0.1524)
				(type default)
			)
			(layer "F.SilkS")
		)
		(fp_rect
			(start -0.508 0.9398)
			(end 0.508 -0.9398)
			(stroke
				(width 0)
				(type default)
			)
			(fill no)
			(layer "F.CrtYd")
		)
		(fp_rect
			(start -0.508 0.9398)
			(end 0.508 -0.9398)
			(stroke
				(width 0)
				(type default)
			)
			(fill no)
			(layer "F.Fab")
		)
		(pad "1" smd custom
			(at 0 -0.4445 180)
			(size 0.1397 0.1397)
			(layers "F.Cu" "F.Mask" "F.Paste")
			(net "P3V3")
			(options
				(clearance outline)
				(anchor circle)
			)
			(primitives
				(gr_poly
					(pts
						(arc
							(start -0.1778 -0.2794)
							(mid -0.249642 -0.249642)
							(end -0.2794 -0.1778)
						)
						(arc
							(start -0.2794 0.1778)
							(mid -0.249642 0.249642)
							(end -0.1778 0.2794)
						)
						(arc
							(start 0.1778 0.2794)
							(mid 0.249642 0.249642)
							(end 0.2794 0.1778)
						)
						(arc
							(start 0.2794 -0.1778)
							(mid 0.249642 -0.249642)
							(end 0.1778 -0.2794)
						)
					)
					(width 0)
					(fill yes)
				)
			)
		)
		(pad "2" smd custom
			(at 0 0.4445 180)
			(size 0.1397 0.1397)
			(layers "F.Cu" "F.Mask" "F.Paste")
			(net "I2C_C_BUF_SCLOUT")
			(options
				(clearance outline)
				(anchor circle)
			)
			(primitives
				(gr_poly
					(pts
						(arc
							(start -0.1778 -0.2794)
							(mid -0.249642 -0.249642)
							(end -0.2794 -0.1778)
						)
						(arc
							(start -0.2794 0.1778)
							(mid -0.249642 0.249642)
							(end -0.1778 0.2794)
						)
						(arc
							(start 0.1778 0.2794)
							(mid 0.249642 0.249642)
							(end 0.2794 0.1778)
						)
						(arc
							(start 0.2794 -0.1778)
							(mid 0.249642 -0.249642)
							(end 0.1778 -0.2794)
						)
					)
					(width 0)
					(fill yes)
				)
			)
		)
	)
	(footprint ""
		(layer "F.Cu")
		(at 12.977876 -98.81235)
		(property "Reference" "R344"
			(at 0 0 0)
			(layer "F.SilkS")
			(hide yes)
			(effects
				(font
					(size 1.27 1.27)
				)
			)
		)
		(property "Value" "10KR2F-2-GP"
			(at 0.064008 -3.993896 0)
			(unlocked yes)
			(layer "F.Fab")
			(hide yes)
			(effects
				(font
					(size 1.016 1.016)
					(thickness 0.1524)
				)
			)
		)
		(property "Device Type" "R402H16"
			(at 0.064008 -5.517896 0)
			(unlocked yes)
			(layer "F.Fab")
			(hide yes)
			(effects
				(font
					(size 1.016 1.016)
					(thickness 0.1524)
				)
			)
		)
		(duplicate_pad_numbers_are_jumpers no)
		(fp_line
			(start -0.508 -0.9398)
			(end -0.508 0.9398)
			(stroke
				(width 0.1524)
				(type default)
			)
			(layer "F.SilkS")
		)
		(fp_line
			(start 0.508 -0.9398)
			(end -0.508 -0.9398)
			(stroke
				(width 0.1524)
				(type default)
			)
			(layer "F.SilkS")
		)
		(fp_rect
			(start -0.508 0.9398)
			(end 0.508 -0.9398)
			(stroke
				(width 0)
				(type default)
			)
			(fill no)
			(layer "F.CrtYd")
		)
		(fp_rect
			(start -0.508 0.9398)
			(end 0.508 -0.9398)
			(stroke
				(width 0)
				(type default)
			)
			(fill no)
			(layer "F.Fab")
		)
		(pad "1" smd custom
			(at 0 -0.4445)
			(size 0.1397 0.1397)
			(layers "F.Cu" "F.Mask" "F.Paste")
			(net "P3V3")
			(options
				(clearance outline)
				(anchor circle)
			)
			(primitives
				(gr_poly
					(pts
						(arc
							(start -0.1778 -0.2794)
							(mid -0.249642 -0.249642)
							(end -0.2794 -0.1778)
						)
						(arc
							(start -0.2794 0.1778)
							(mid -0.249642 0.249642)
							(end -0.1778 0.2794)
						)
						(arc
							(start 0.1778 0.2794)
							(mid 0.249642 0.249642)
							(end 0.2794 0.1778)
						)
						(arc
							(start 0.2794 -0.1778)
							(mid 0.249642 -0.249642)
							(end 0.1778 -0.2794)
						)
					)
					(width 0)
					(fill yes)
				)
			)
		)
		(pad "2" smd custom
			(at 0 0.4445)
			(size 0.1397 0.1397)
			(layers "F.Cu" "F.Mask" "F.Paste")
			(net "I2C_C_BUF_SDAOUT")
			(options
				(clearance outline)
				(anchor circle)
			)
			(primitives
				(gr_poly
					(pts
						(arc
							(start -0.1778 -0.2794)
							(mid -0.249642 -0.249642)
							(end -0.2794 -0.1778)
						)
						(arc
							(start -0.2794 0.1778)
							(mid -0.249642 0.249642)
							(end -0.1778 0.2794)
						)
						(arc
							(start 0.1778 0.2794)
							(mid 0.249642 0.249642)
							(end 0.2794 0.1778)
						)
						(arc
							(start 0.2794 -0.1778)
							(mid 0.249642 -0.249642)
							(end 0.1778 -0.2794)
						)
					)
					(width 0)
					(fill yes)
				)
			)
		)
	)
	(footprint ""
		(layer "F.Cu")
		(at 135.086344 -83.972908 90)
		(property "Reference" "R365"
			(at 0 0 90)
			(layer "F.SilkS")
			(hide yes)
			(effects
				(font
					(size 1.27 1.27)
				)
			)
		)
		(property "Value" "0R2J-2-GP"
			(at 0.064008 -3.993896 90)
			(unlocked yes)
			(layer "F.Fab")
			(hide yes)
			(effects
				(font
					(size 1.016 1.016)
					(thickness 0.1524)
				)
			)
		)
		(property "Device Type" "R402H16"
			(at 0.064008 -5.517896 90)
			(unlocked yes)
			(layer "F.Fab")
			(hide yes)
			(effects
				(font
					(size 1.016 1.016)
					(thickness 0.1524)
				)
			)
		)
		(duplicate_pad_numbers_are_jumpers no)
		(fp_line
			(start 0.508 -0.9398)
			(end -0.508 -0.9398)
			(stroke
				(width 0.1524)
				(type default)
			)
			(layer "F.SilkS")
		)
		(fp_line
			(start -0.508 -0.9398)
			(end -0.508 0.9398)
			(stroke
				(width 0.1524)
				(type default)
			)
			(layer "F.SilkS")
		)
		(fp_rect
			(start -0.508 0.9398)
			(end 0.508 -0.9398)
			(stroke
				(width 0)
				(type default)
			)
			(fill no)
			(layer "F.CrtYd")
		)
		(fp_rect
			(start -0.508 0.9398)
			(end 0.508 -0.9398)
			(stroke
				(width 0)
				(type default)
			)
			(fill no)
			(layer "F.Fab")
		)
		(pad "1" smd custom
			(at 0 -0.4445 90)
			(size 0.1397 0.1397)
			(layers "F.Cu" "F.Mask" "F.Paste")
			(net "TRAY PRESENT_OUT_NET")
			(options
				(clearance outline)
				(anchor circle)
			)
			(primitives
				(gr_poly
					(pts
						(arc
							(start -0.1778 -0.2794)
							(mid -0.249642 -0.249642)
							(end -0.2794 -0.1778)
						)
						(arc
							(start -0.2794 0.1778)
							(mid -0.249642 0.249642)
							(end -0.1778 0.2794)
						)
						(arc
							(start 0.1778 0.2794)
							(mid 0.249642 0.249642)
							(end 0.2794 0.1778)
						)
						(arc
							(start 0.2794 -0.1778)
							(mid 0.249642 -0.249642)
							(end 0.1778 -0.2794)
						)
					)
					(width 0)
					(fill yes)
				)
			)
		)
		(pad "2" smd custom
			(at 0 0.4445 90)
			(size 0.1397 0.1397)
			(layers "F.Cu" "F.Mask" "F.Paste")
			(net "TRAY_MOSFET_G")
			(options
				(clearance outline)
				(anchor circle)
			)
			(primitives
				(gr_poly
					(pts
						(arc
							(start -0.1778 -0.2794)
							(mid -0.249642 -0.249642)
							(end -0.2794 -0.1778)
						)
						(arc
							(start -0.2794 0.1778)
							(mid -0.249642 0.249642)
							(end -0.1778 0.2794)
						)
						(arc
							(start 0.1778 0.2794)
							(mid 0.249642 0.249642)
							(end 0.2794 0.1778)
						)
						(arc
							(start 0.2794 -0.1778)
							(mid 0.249642 -0.249642)
							(end 0.1778 -0.2794)
						)
					)
					(width 0)
					(fill yes)
				)
			)
		)
	)
	(footprint ""
		(layer "F.Cu")
		(at 136.152382 -68.318634 90)
		(property "Reference" "R386"
			(at 0 0 90)
			(layer "F.SilkS")
			(hide yes)
			(effects
				(font
					(size 1.27 1.27)
				)
			)
		)
		(property "Value" "0R2J-2-GP"
			(at 0.064008 -3.993896 90)
			(unlocked yes)
			(layer "F.Fab")
			(hide yes)
			(effects
				(font
					(size 1.016 1.016)
					(thickness 0.1524)
				)
			)
		)
		(property "Device Type" "R402H16"
			(at 0.064008 -5.517896 90)
			(unlocked yes)
			(layer "F.Fab")
			(hide yes)
			(effects
				(font
					(size 1.016 1.016)
					(thickness 0.1524)
				)
			)
		)
		(duplicate_pad_numbers_are_jumpers no)
		(fp_line
			(start 0.508 -0.9398)
			(end -0.508 -0.9398)
			(stroke
				(width 0.1524)
				(type default)
			)
			(layer "F.SilkS")
		)
		(fp_line
			(start -0.508 -0.9398)
			(end -0.508 0.9398)
			(stroke
				(width 0.1524)
				(type default)
			)
			(layer "F.SilkS")
		)
		(fp_rect
			(start -0.508 0.9398)
			(end 0.508 -0.9398)
			(stroke
				(width 0)
				(type default)
			)
			(fill no)
			(layer "F.CrtYd")
		)
		(fp_rect
			(start -0.508 0.9398)
			(end 0.508 -0.9398)
			(stroke
				(width 0)
				(type default)
			)
			(fill no)
			(layer "F.Fab")
		)
		(pad "1" smd custom
			(at 0 -0.4445 90)
			(size 0.1397 0.1397)
			(layers "F.Cu" "F.Mask" "F.Paste")
			(net "I2C_C_BUF_SDA")
			(options
				(clearance outline)
				(anchor circle)
			)
			(primitives
				(gr_poly
					(pts
						(arc
							(start -0.1778 -0.2794)
							(mid -0.249642 -0.249642)
							(end -0.2794 -0.1778)
						)
						(arc
							(start -0.2794 0.1778)
							(mid -0.249642 0.249642)
							(end -0.1778 0.2794)
						)
						(arc
							(start 0.1778 0.2794)
							(mid 0.249642 0.249642)
							(end 0.2794 0.1778)
						)
						(arc
							(start 0.2794 -0.1778)
							(mid 0.249642 -0.249642)
							(end 0.1778 -0.2794)
						)
					)
					(width 0)
					(fill yes)
				)
			)
		)
		(pad "2" smd custom
			(at 0 0.4445 90)
			(size 0.1397 0.1397)
			(layers "F.Cu" "F.Mask" "F.Paste")
			(net "I2C_C_BUF_SDA_CONN")
			(options
				(clearance outline)
				(anchor circle)
			)
			(primitives
				(gr_poly
					(pts
						(arc
							(start -0.1778 -0.2794)
							(mid -0.249642 -0.249642)
							(end -0.2794 -0.1778)
						)
						(arc
							(start -0.2794 0.1778)
							(mid -0.249642 0.249642)
							(end -0.1778 0.2794)
						)
						(arc
							(start 0.1778 0.2794)
							(mid 0.249642 0.249642)
							(end 0.2794 0.1778)
						)
						(arc
							(start 0.2794 -0.1778)
							(mid 0.249642 -0.249642)
							(end 0.1778 -0.2794)
						)
					)
					(width 0)
					(fill yes)
				)
			)
		)
	)
)
